# T6G (Grand Teton) — schematic netlist excerpt (pin names and nets, part order shuffled) for the footprints in the layout excerpt that follows; sources: Cadence DE-HDL packaged netlist, KiCad conversion of 04192023_DAF0TMB3IC0_F0TG_MB_C_brd_V02_OCP.brd

C2356  Q_CAP  22UF 4V 20% X6S  pkg C0402  page 73 : A = PVDDCR_CPU1_P1 ; B = GND
C161  Q_CAP  10UF 25V 10% X6S  pkg C0805  page 93 : A = P12V_MEM_CPU0 ; B = GND
C2386  Q_CAP  22UF 4V 20% X6S  pkg C0402  page 73 : A = PVDDCR_CPU1_P1 ; B = GND

(kicad_pcb
	(version 20260206)
	(generator "pcbnew")
	(generator_version "10.0")
	(general
		(thickness 1.6)
		(legacy_teardrops no)
	)
	(paper "A4")
	(title_block
		(title "04192023_DAF0TMB3IC0_F0TG_MB_C_brd_V02_OCP.brd")
		(comment 1 "Grand Teton / footprints 5604-5606 of 8354")
	)
	(layers
		(0 "F.Cu" signal "TOP")
		(4 "In1.Cu" signal "GND")
		(6 "In2.Cu" signal "IN1")
		(8 "In3.Cu" signal "GND1")
		(10 "In4.Cu" signal "IN2")
		(12 "In5.Cu" signal "GND2")
		(14 "In6.Cu" signal "IN3")
		(16 "In7.Cu" signal "GND3")
		(18 "In8.Cu" signal "VCC")
		(20 "In9.Cu" signal "VCC1")
		(22 "In10.Cu" signal "GND4")
		(24 "In11.Cu" signal "IN4")
		(26 "In12.Cu" signal "GND5")
		(28 "In13.Cu" signal "IN5")
		(30 "In14.Cu" signal "GND6")
		(32 "In15.Cu" signal "IN6")
		(34 "In16.Cu" signal "GND7")
		(2 "B.Cu" signal "BOTTOM")
		(9 "F.Adhes" user "F.Adhesive")
		(11 "B.Adhes" user "B.Adhesive")
		(13 "F.Paste" user "Package Geometry/Pastemask Top")
		(15 "B.Paste" user "Package Geometry/Pastemask Bottom")
		(5 "F.SilkS" user "Ref Des/Silkscreen Top")
		(7 "B.SilkS" user "Ref Des/Silkscreen Bottom")
		(1 "F.Mask" user "Board Geometry/Soldermask Top")
		(3 "B.Mask" user "Board Geometry/Soldermask Bottom")
		(17 "Dwgs.User" user "User.Drawings")
		(19 "Cmts.User" user "User.Comments")
		(21 "Eco1.User" user "User.Eco1")
		(23 "Eco2.User" user "User.Eco2")
		(25 "Edge.Cuts" user "Board Geometry/Outline")
		(27 "Margin" user)
		(31 "F.CrtYd" user "Package Geometry/Place Bound Top")
		(29 "B.CrtYd" user "Package Geometry/Place Bound Bottom")
		(35 "F.Fab" user "Ref Des/Assembly Top")
		(33 "B.Fab" user "Ref Des/Assembly Bottom")
	)
	(footprint ""
		(layer "B.Cu")
		(at 123.970034 -271.853152 90)
		(property "Reference" "C2386"
			(at 0 0 90)
			(layer "B.SilkS")
			(hide yes)
			(effects
				(font
					(size 1.27 1.27)
				)
				(justify mirror)
			)
		)
		(property "Value" ""
			(at 0 0 90)
			(layer "B.Fab")
			(effects
				(font
					(size 1.27 1.27)
				)
				(justify mirror)
			)
		)
		(duplicate_pad_numbers_are_jumpers no)
		(fp_line
			(start 0.7874 -0.4064)
			(end -0.7874 -0.4064)
			(stroke
				(width 0.1524)
				(type default)
			)
			(layer "B.SilkS")
		)
		(fp_line
			(start -0.7874 -0.4064)
			(end -0.7874 0.4064)
			(stroke
				(width 0.1524)
				(type default)
			)
			(layer "B.SilkS")
		)
		(fp_line
			(start 0.7874 0.4064)
			(end 0.7874 -0.4064)
			(stroke
				(width 0.1524)
				(type default)
			)
			(layer "B.SilkS")
		)
		(fp_line
			(start -0.7874 0.4064)
			(end 0.7874 0.4064)
			(stroke
				(width 0.1524)
				(type default)
			)
			(layer "B.SilkS")
		)
		(fp_line
			(start 0.67945 -0.305054)
			(end 0.12065 -0.305054)
			(stroke
				(width 0.1)
				(type default)
			)
			(layer "B.Fab")
		)
		(fp_line
			(start 0.12065 -0.305054)
			(end 0.12065 -0.2794)
			(stroke
				(width 0.1)
				(type default)
			)
			(layer "B.Fab")
		)
		(fp_line
			(start -0.12065 -0.3048)
			(end -0.67945 -0.3048)
			(stroke
				(width 0.1)
				(type default)
			)
			(layer "B.Fab")
		)
		(fp_line
			(start -0.67945 -0.3048)
			(end -0.67945 0.3048)
			(stroke
				(width 0.1)
				(type default)
			)
			(layer "B.Fab")
		)
		(fp_line
			(start 0.12065 -0.2794)
			(end -0.12065 -0.2794)
			(stroke
				(width 0.1)
				(type default)
			)
			(layer "B.Fab")
		)
		(fp_line
			(start -0.12065 -0.2794)
			(end -0.12065 -0.3048)
			(stroke
				(width 0.1)
				(type default)
			)
			(layer "B.Fab")
		)
		(fp_line
			(start 0.12065 0.2794)
			(end 0.12065 0.3048)
			(stroke
				(width 0.1)
				(type default)
			)
			(layer "B.Fab")
		)
		(fp_line
			(start -0.120396 0.2794)
			(end 0.12065 0.2794)
			(stroke
				(width 0.1)
				(type default)
			)
			(layer "B.Fab")
		)
		(fp_line
			(start 0.67945 0.3048)
			(end 0.67945 -0.305054)
			(stroke
				(width 0.1)
				(type default)
			)
			(layer "B.Fab")
		)
		(fp_line
			(start 0.12065 0.3048)
			(end 0.67945 0.3048)
			(stroke
				(width 0.1)
				(type default)
			)
			(layer "B.Fab")
		)
		(fp_line
			(start -0.120396 0.3048)
			(end -0.120396 0.2794)
			(stroke
				(width 0.1)
				(type default)
			)
			(layer "B.Fab")
		)
		(fp_line
			(start -0.67945 0.3048)
			(end -0.120396 0.3048)
			(stroke
				(width 0.1)
				(type default)
			)
			(layer "B.Fab")
		)
		(pad "1" smd circle
			(at 0.40005 0 270)
			(size 0 0)
			(layers "B.Cu" "B.Mask" "B.Paste")
			(net "PVDDCR_CPU1_P1")
		)
		(pad "2" smd circle
			(at -0.40005 0 270)
			(size 0 0)
			(layers "B.Cu" "B.Mask" "B.Paste")
			(net "GND")
		)
	)
	(footprint ""
		(layer "B.Cu")
		(at 419.912038 -192.660016 180)
		(property "Reference" "C161"
			(at 0 0 0)
			(layer "B.SilkS")
			(hide yes)
			(effects
				(font
					(size 1.27 1.27)
				)
				(justify mirror)
			)
		)
		(property "Value" ""
			(at 0 0 0)
			(layer "B.Fab")
			(effects
				(font
					(size 1.27 1.27)
				)
				(justify mirror)
			)
		)
		(duplicate_pad_numbers_are_jumpers no)
		(fp_line
			(start 1.524 0.762)
			(end 1.524 -0.762)
			(stroke
				(width 0.1524)
				(type default)
			)
			(layer "B.SilkS")
		)
		(fp_line
			(start 1.524 -0.762)
			(end -1.524 -0.762)
			(stroke
				(width 0.1524)
				(type default)
			)
			(layer "B.SilkS")
		)
		(fp_line
			(start -1.524 0.762)
			(end 1.524 0.762)
			(stroke
				(width 0.1524)
				(type default)
			)
			(layer "B.SilkS")
		)
		(fp_line
			(start -1.524 -0.762)
			(end -1.524 0.762)
			(stroke
				(width 0.1524)
				(type default)
			)
			(layer "B.SilkS")
		)
		(fp_line
			(start 1.1049 0.724916)
			(end -1.1049 0.724916)
			(stroke
				(width 0.1)
				(type default)
			)
			(layer "B.Fab")
		)
		(fp_line
			(start 1.1049 -0.724916)
			(end 1.1049 0.724916)
			(stroke
				(width 0.1)
				(type default)
			)
			(layer "B.Fab")
		)
		(fp_line
			(start -1.1049 0.724916)
			(end -1.1049 -0.724916)
			(stroke
				(width 0.1)
				(type default)
			)
			(layer "B.Fab")
		)
		(fp_line
			(start -1.1049 -0.724916)
			(end 1.1049 -0.724916)
			(stroke
				(width 0.1)
				(type default)
			)
			(layer "B.Fab")
		)
		(pad "1" smd rect
			(at 0.889 0 180)
			(size 1.016 1.27)
			(layers "B.Cu" "B.Mask" "B.Paste")
			(net "P12V_MEM_CPU0")
		)
		(pad "2" smd rect
			(at -0.889 0 180)
			(size 1.016 1.27)
			(layers "B.Cu" "B.Mask" "B.Paste")
			(net "GND")
		)
	)
	(footprint ""
		(layer "B.Cu")
		(at 118.686834 -272.284952 180)
		(property "Reference" "C2356"
			(at 0 0 0)
			(layer "B.SilkS")
			(hide yes)
			(effects
				(font
					(size 1.27 1.27)
				)
				(justify mirror)
			)
		)
		(property "Value" ""
			(at 0 0 0)
			(layer "B.Fab")
			(effects
				(font
					(size 1.27 1.27)
				)
				(justify mirror)
			)
		)
		(duplicate_pad_numbers_are_jumpers no)
		(fp_line
			(start 0.7874 0.4064)
			(end 0.7874 -0.4064)
			(stroke
				(width 0.1524)
				(type default)
			)
			(layer "B.SilkS")
		)
		(fp_line
			(start 0.7874 -0.4064)
			(end -0.7874 -0.4064)
			(stroke
				(width 0.1524)
				(type default)
			)
			(layer "B.SilkS")
		)
		(fp_line
			(start -0.7874 0.4064)
			(end 0.7874 0.4064)
			(stroke
				(width 0.1524)
				(type default)
			)
			(layer "B.SilkS")
		)
		(fp_line
			(start -0.7874 -0.4064)
			(end -0.7874 0.4064)
			(stroke
				(width 0.1524)
				(type default)
			)
			(layer "B.SilkS")
		)
		(fp_line
			(start 0.67945 0.3048)
			(end 0.67945 -0.305054)
			(stroke
				(width 0.1)
				(type default)
			)
			(layer "B.Fab")
		)
		(fp_line
			(start 0.67945 -0.305054)
			(end 0.12065 -0.305054)
			(stroke
				(width 0.1)
				(type default)
			)
			(layer "B.Fab")
		)
		(fp_line
			(start 0.12065 0.3048)
			(end 0.67945 0.3048)
			(stroke
				(width 0.1)
				(type default)
			)
			(layer "B.Fab")
		)
		(fp_line
			(start 0.12065 0.2794)
			(end 0.12065 0.3048)
			(stroke
				(width 0.1)
				(type default)
			)
			(layer "B.Fab")
		)
		(fp_line
			(start 0.12065 -0.2794)
			(end -0.12065 -0.2794)
			(stroke
				(width 0.1)
				(type default)
			)
			(layer "B.Fab")
		)
		(fp_line
			(start 0.12065 -0.305054)
			(end 0.12065 -0.2794)
			(stroke
				(width 0.1)
				(type default)
			)
			(layer "B.Fab")
		)
		(fp_line
			(start -0.120396 0.3048)
			(end -0.120396 0.2794)
			(stroke
				(width 0.1)
				(type default)
			)
			(layer "B.Fab")
		)
		(fp_line
			(start -0.120396 0.2794)
			(end 0.12065 0.2794)
			(stroke
				(width 0.1)
				(type default)
			)
			(layer "B.Fab")
		)
		(fp_line
			(start -0.12065 -0.2794)
			(end -0.12065 -0.3048)
			(stroke
				(width 0.1)
				(type default)
			)
			(layer "B.Fab")
		)
		(fp_line
			(start -0.12065 -0.3048)
			(end -0.67945 -0.3048)
			(stroke
				(width 0.1)
				(type default)
			)
			(layer "B.Fab")
		)
		(fp_line
			(start -0.67945 0.3048)
			(end -0.120396 0.3048)
			(stroke
				(width 0.1)
				(type default)
			)
			(layer "B.Fab")
		)
		(fp_line
			(start -0.67945 -0.3048)
			(end -0.67945 0.3048)
			(stroke
				(width 0.1)
				(type default)
			)
			(layer "B.Fab")
		)
		(pad "1" smd circle
			(at 0.40005 0)
			(size 0 0)
			(layers "B.Cu" "B.Mask" "B.Paste")
			(net "PVDDCR_CPU1_P1")
		)
		(pad "2" smd circle
			(at -0.40005 0)
			(size 0 0)
			(layers "B.Cu" "B.Mask" "B.Paste")
			(net "GND")
		)
	)
)
